# T6G (Grand Teton) — schematic netlist excerpt (pin names and nets, part order shuffled) for the footprints in the layout excerpt that follows; sources: Cadence DE-HDL packaged netlist, KiCad conversion of 04192023_DAF0TMB3IC0_F0TG_MB_C_brd_V02_OCP.brd

R2831  Q_RES  100K 1% EMPTY  pkg 0402LF  page 127 : A = BIC_MONITER ; B = GND
PR2531  Q_RES  10 1% CHIP  pkg 0402LF  page 266 : A = P12V_HSC_GATE_G4 ; B = P12V_HSC_GATE2

(kicad_pcb
	(version 20260206)
	(generator "pcbnew")
	(generator_version "10.0")
	(general
		(thickness 1.6)
		(legacy_teardrops no)
	)
	(paper "A4")
	(title_block
		(title "04192023_DAF0TMB3IC0_F0TG_MB_C_brd_V02_OCP.brd")
		(comment 1 "Grand Teton / footprints 85-86 of 8354")
	)
	(layers
		(0 "F.Cu" signal "TOP")
		(4 "In1.Cu" signal "GND")
		(6 "In2.Cu" signal "IN1")
		(8 "In3.Cu" signal "GND1")
		(10 "In4.Cu" signal "IN2")
		(12 "In5.Cu" signal "GND2")
		(14 "In6.Cu" signal "IN3")
		(16 "In7.Cu" signal "GND3")
		(18 "In8.Cu" signal "VCC")
		(20 "In9.Cu" signal "VCC1")
		(22 "In10.Cu" signal "GND4")
		(24 "In11.Cu" signal "IN4")
		(26 "In12.Cu" signal "GND5")
		(28 "In13.Cu" signal "IN5")
		(30 "In14.Cu" signal "GND6")
		(32 "In15.Cu" signal "IN6")
		(34 "In16.Cu" signal "GND7")
		(2 "B.Cu" signal "BOTTOM")
		(9 "F.Adhes" user "F.Adhesive")
		(11 "B.Adhes" user "B.Adhesive")
		(13 "F.Paste" user "Package Geometry/Pastemask Top")
		(15 "B.Paste" user "Package Geometry/Pastemask Bottom")
		(5 "F.SilkS" user "Ref Des/Silkscreen Top")
		(7 "B.SilkS" user "Ref Des/Silkscreen Bottom")
		(1 "F.Mask" user "Board Geometry/Soldermask Top")
		(3 "B.Mask" user "Board Geometry/Soldermask Bottom")
		(17 "Dwgs.User" user "User.Drawings")
		(19 "Cmts.User" user "User.Comments")
		(21 "Eco1.User" user "User.Eco1")
		(23 "Eco2.User" user "User.Eco2")
		(25 "Edge.Cuts" user "Board Geometry/Outline")
		(27 "Margin" user)
		(31 "F.CrtYd" user "Package Geometry/Place Bound Top")
		(29 "B.CrtYd" user "Package Geometry/Place Bound Bottom")
		(35 "F.Fab" user "Ref Des/Assembly Top")
		(33 "B.Fab" user "Ref Des/Assembly Bottom")
	)
	(footprint ""
		(layer "F.Cu")
		(at 165.2016 -440.182)
		(property "Reference" "R2831"
			(at 0 0 0)
			(layer "F.SilkS")
			(hide yes)
			(effects
				(font
					(size 1.27 1.27)
				)
			)
		)
		(property "Value" ""
			(at 0 0 0)
			(layer "F.Fab")
			(effects
				(font
					(size 1.27 1.27)
				)
			)
		)
		(duplicate_pad_numbers_are_jumpers no)
		(fp_line
			(start -0.7874 -0.4064)
			(end 0.7874 -0.4064)
			(stroke
				(width 0.1524)
				(type default)
			)
			(layer "F.SilkS")
		)
		(fp_line
			(start -0.7874 0.4064)
			(end -0.7874 -0.4064)
			(stroke
				(width 0.1524)
				(type default)
			)
			(layer "F.SilkS")
		)
		(fp_line
			(start 0.7874 -0.4064)
			(end 0.7874 0.4064)
			(stroke
				(width 0.1524)
				(type default)
			)
			(layer "F.SilkS")
		)
		(fp_line
			(start 0.7874 0.4064)
			(end -0.7874 0.4064)
			(stroke
				(width 0.1524)
				(type default)
			)
			(layer "F.SilkS")
		)
		(fp_line
			(start -0.67945 -0.305054)
			(end -0.12065 -0.305054)
			(stroke
				(width 0.1)
				(type default)
			)
			(layer "F.Fab")
		)
		(fp_line
			(start -0.67945 0.3048)
			(end -0.67945 -0.305054)
			(stroke
				(width 0.1)
				(type default)
			)
			(layer "F.Fab")
		)
		(fp_line
			(start -0.12065 -0.305054)
			(end -0.12065 -0.2794)
			(stroke
				(width 0.1)
				(type default)
			)
			(layer "F.Fab")
		)
		(fp_line
			(start -0.12065 -0.2794)
			(end 0.12065 -0.2794)
			(stroke
				(width 0.1)
				(type default)
			)
			(layer "F.Fab")
		)
		(fp_line
			(start -0.12065 0.2794)
			(end -0.12065 0.3048)
			(stroke
				(width 0.1)
				(type default)
			)
			(layer "F.Fab")
		)
		(fp_line
			(start -0.12065 0.3048)
			(end -0.67945 0.3048)
			(stroke
				(width 0.1)
				(type default)
			)
			(layer "F.Fab")
		)
		(fp_line
			(start 0.120396 0.2794)
			(end -0.12065 0.2794)
			(stroke
				(width 0.1)
				(type default)
			)
			(layer "F.Fab")
		)
		(fp_line
			(start 0.120396 0.3048)
			(end 0.120396 0.2794)
			(stroke
				(width 0.1)
				(type default)
			)
			(layer "F.Fab")
		)
		(fp_line
			(start 0.12065 -0.3048)
			(end 0.67945 -0.3048)
			(stroke
				(width 0.1)
				(type default)
			)
			(layer "F.Fab")
		)
		(fp_line
			(start 0.12065 -0.2794)
			(end 0.12065 -0.3048)
			(stroke
				(width 0.1)
				(type default)
			)
			(layer "F.Fab")
		)
		(fp_line
			(start 0.67945 -0.3048)
			(end 0.67945 0.3048)
			(stroke
				(width 0.1)
				(type default)
			)
			(layer "F.Fab")
		)
		(fp_line
			(start 0.67945 0.3048)
			(end 0.120396 0.3048)
			(stroke
				(width 0.1)
				(type default)
			)
			(layer "F.Fab")
		)
		(pad "1" smd circle
			(at -0.40005 0)
			(size 0 0)
			(layers "F.Cu" "F.Mask" "F.Paste")
			(net "BIC_MONITER")
		)
		(pad "2" smd circle
			(at 0.40005 0)
			(size 0 0)
			(layers "F.Cu" "F.Mask" "F.Paste")
			(net "GND")
		)
	)
	(footprint ""
		(layer "F.Cu")
		(at 273.635978 -380.66853)
		(property "Reference" "PR2531"
			(at 0 0 0)
			(layer "F.SilkS")
			(hide yes)
			(effects
				(font
					(size 1.27 1.27)
				)
			)
		)
		(property "Value" ""
			(at 0 0 0)
			(layer "F.Fab")
			(effects
				(font
					(size 1.27 1.27)
				)
			)
		)
		(duplicate_pad_numbers_are_jumpers no)
		(fp_line
			(start -0.7874 -0.4064)
			(end 0.7874 -0.4064)
			(stroke
				(width 0.1524)
				(type default)
			)
			(layer "F.SilkS")
		)
		(fp_line
			(start -0.7874 0.4064)
			(end -0.7874 -0.4064)
			(stroke
				(width 0.1524)
				(type default)
			)
			(layer "F.SilkS")
		)
		(fp_line
			(start 0.7874 -0.4064)
			(end 0.7874 0.4064)
			(stroke
				(width 0.1524)
				(type default)
			)
			(layer "F.SilkS")
		)
		(fp_line
			(start 0.7874 0.4064)
			(end -0.7874 0.4064)
			(stroke
				(width 0.1524)
				(type default)
			)
			(layer "F.SilkS")
		)
		(fp_line
			(start -0.67945 -0.305054)
			(end -0.12065 -0.305054)
			(stroke
				(width 0.1)
				(type default)
			)
			(layer "F.Fab")
		)
		(fp_line
			(start -0.67945 0.3048)
			(end -0.67945 -0.305054)
			(stroke
				(width 0.1)
				(type default)
			)
			(layer "F.Fab")
		)
		(fp_line
			(start -0.12065 -0.305054)
			(end -0.12065 -0.2794)
			(stroke
				(width 0.1)
				(type default)
			)
			(layer "F.Fab")
		)
		(fp_line
			(start -0.12065 -0.2794)
			(end 0.12065 -0.2794)
			(stroke
				(width 0.1)
				(type default)
			)
			(layer "F.Fab")
		)
		(fp_line
			(start -0.12065 0.2794)
			(end -0.12065 0.3048)
			(stroke
				(width 0.1)
				(type default)
			)
			(layer "F.Fab")
		)
		(fp_line
			(start -0.12065 0.3048)
			(end -0.67945 0.3048)
			(stroke
				(width 0.1)
				(type default)
			)
			(layer "F.Fab")
		)
		(fp_line
			(start 0.120396 0.2794)
			(end -0.12065 0.2794)
			(stroke
				(width 0.1)
				(type default)
			)
			(layer "F.Fab")
		)
		(fp_line
			(start 0.120396 0.3048)
			(end 0.120396 0.2794)
			(stroke
				(width 0.1)
				(type default)
			)
			(layer "F.Fab")
		)
		(fp_line
			(start 0.12065 -0.3048)
			(end 0.67945 -0.3048)
			(stroke
				(width 0.1)
				(type default)
			)
			(layer "F.Fab")
		)
		(fp_line
			(start 0.12065 -0.2794)
			(end 0.12065 -0.3048)
			(stroke
				(width 0.1)
				(type default)
			)
			(layer "F.Fab")
		)
		(fp_line
			(start 0.67945 -0.3048)
			(end 0.67945 0.3048)
			(stroke
				(width 0.1)
				(type default)
			)
			(layer "F.Fab")
		)
		(fp_line
			(start 0.67945 0.3048)
			(end 0.120396 0.3048)
			(stroke
				(width 0.1)
				(type default)
			)
			(layer "F.Fab")
		)
		(pad "1" smd circle
			(at -0.40005 0)
			(size 0 0)
			(layers "F.Cu" "F.Mask" "F.Paste")
			(net "P12V_HSC_GATE_G4")
		)
		(pad "2" smd circle
			(at 0.40005 0)
			(size 0 0)
			(layers "F.Cu" "F.Mask" "F.Paste")
			(net "P12V_HSC_GATE2")
		)
	)
)
